# T6G (Grand Teton) — schematic netlist excerpt (pin names and nets, part order shuffled) for the footprints in the layout excerpt that follows; sources: Cadence DE-HDL packaged netlist, KiCad conversion of 04192023_DAF0TMB3IC0_F0TG_MB_C_brd_V02_OCP.brd

C6581  Q_CAP_DIFFBUS  DIFF BUS_0.22UF 6.3V 20% X6S  pkg C0201  page 297 : \1\ = P5E_CPU0_P2_TX_BUF_C_DP<8> ; \2\ = P5E_CPU0_P2_TX_BUF_DP<8>
PL19  Q_INDUCTOR  50NH/86A IND  pkg SMLF  page 205 : \1\ = SW_P12V_AUX_PVDDIO_P0_FLT ; \2\ = P12V_AUX
R1646  Q_RES  1K 1% CHIP  pkg 0402LF  page 174 : A = PVDD18_S5_P0 ; B = CPU0_HDT_BYPASS_SEL

(kicad_pcb
	(version 20260206)
	(generator "pcbnew")
	(generator_version "10.0")
	(general
		(thickness 1.6)
		(legacy_teardrops no)
	)
	(paper "A4")
	(title_block
		(title "04192023_DAF0TMB3IC0_F0TG_MB_C_brd_V02_OCP.brd")
		(comment 1 "Grand Teton / footprints 2857-2859 of 8354")
	)
	(layers
		(0 "F.Cu" signal "TOP")
		(4 "In1.Cu" signal "GND")
		(6 "In2.Cu" signal "IN1")
		(8 "In3.Cu" signal "GND1")
		(10 "In4.Cu" signal "IN2")
		(12 "In5.Cu" signal "GND2")
		(14 "In6.Cu" signal "IN3")
		(16 "In7.Cu" signal "GND3")
		(18 "In8.Cu" signal "VCC")
		(20 "In9.Cu" signal "VCC1")
		(22 "In10.Cu" signal "GND4")
		(24 "In11.Cu" signal "IN4")
		(26 "In12.Cu" signal "GND5")
		(28 "In13.Cu" signal "IN5")
		(30 "In14.Cu" signal "GND6")
		(32 "In15.Cu" signal "IN6")
		(34 "In16.Cu" signal "GND7")
		(2 "B.Cu" signal "BOTTOM")
		(9 "F.Adhes" user "F.Adhesive")
		(11 "B.Adhes" user "B.Adhesive")
		(13 "F.Paste" user "Package Geometry/Pastemask Top")
		(15 "B.Paste" user "Package Geometry/Pastemask Bottom")
		(5 "F.SilkS" user "Ref Des/Silkscreen Top")
		(7 "B.SilkS" user "Ref Des/Silkscreen Bottom")
		(1 "F.Mask" user "Board Geometry/Soldermask Top")
		(3 "B.Mask" user "Board Geometry/Soldermask Bottom")
		(17 "Dwgs.User" user "User.Drawings")
		(19 "Cmts.User" user "User.Comments")
		(21 "Eco1.User" user "User.Eco1")
		(23 "Eco2.User" user "User.Eco2")
		(25 "Edge.Cuts" user "Board Geometry/Outline")
		(27 "Margin" user)
		(31 "F.CrtYd" user "Package Geometry/Place Bound Top")
		(29 "B.CrtYd" user "Package Geometry/Place Bound Bottom")
		(35 "F.Fab" user "Ref Des/Assembly Top")
		(33 "B.Fab" user "Ref Des/Assembly Bottom")
	)
	(footprint ""
		(layer "F.Cu")
		(at 396.289022 -416.899344 -90)
		(property "Reference" "C6581"
			(at 0 0 270)
			(layer "F.SilkS")
			(hide yes)
			(effects
				(font
					(size 1.27 1.27)
				)
			)
		)
		(property "Value" ""
			(at 0 0 270)
			(layer "F.Fab")
			(effects
				(font
					(size 1.27 1.27)
				)
			)
		)
		(duplicate_pad_numbers_are_jumpers no)
		(fp_line
			(start -0.299974 0.150114)
			(end -0.299974 -0.150114)
			(stroke
				(width 0.1)
				(type default)
			)
			(layer "F.Fab")
		)
		(fp_line
			(start 0.299974 0.150114)
			(end -0.299974 0.150114)
			(stroke
				(width 0.1)
				(type default)
			)
			(layer "F.Fab")
		)
		(fp_line
			(start -0.299974 -0.150114)
			(end 0.299974 -0.150114)
			(stroke
				(width 0.1)
				(type default)
			)
			(layer "F.Fab")
		)
		(fp_line
			(start 0.299974 -0.150114)
			(end 0.299974 0.150114)
			(stroke
				(width 0.1)
				(type default)
			)
			(layer "F.Fab")
		)
		(pad "1" smd rect
			(at -0.2667 0 270)
			(size 0.3048 0.381)
			(layers "F.Cu" "F.Mask" "F.Paste")
			(net "P5E_CPU0_P2_TX_BUF_C_DP<8>")
		)
		(pad "2" smd rect
			(at 0.2667 0 270)
			(size 0.3048 0.381)
			(layers "F.Cu" "F.Mask" "F.Paste")
			(net "P5E_CPU0_P2_TX_BUF_DP<8>")
		)
	)
	(footprint ""
		(layer "F.Cu")
		(at 233.287824 -144.959324)
		(property "Reference" "R1646"
			(at 0 0 0)
			(layer "F.SilkS")
			(hide yes)
			(effects
				(font
					(size 1.27 1.27)
				)
			)
		)
		(property "Value" ""
			(at 0 0 0)
			(layer "F.Fab")
			(effects
				(font
					(size 1.27 1.27)
				)
			)
		)
		(duplicate_pad_numbers_are_jumpers no)
		(fp_line
			(start -0.7874 -0.4064)
			(end 0.7874 -0.4064)
			(stroke
				(width 0.1524)
				(type default)
			)
			(layer "F.SilkS")
		)
		(fp_line
			(start -0.7874 0.4064)
			(end -0.7874 -0.4064)
			(stroke
				(width 0.1524)
				(type default)
			)
			(layer "F.SilkS")
		)
		(fp_line
			(start 0.7874 -0.4064)
			(end 0.7874 0.4064)
			(stroke
				(width 0.1524)
				(type default)
			)
			(layer "F.SilkS")
		)
		(fp_line
			(start 0.7874 0.4064)
			(end -0.7874 0.4064)
			(stroke
				(width 0.1524)
				(type default)
			)
			(layer "F.SilkS")
		)
		(fp_line
			(start -0.67945 -0.305054)
			(end -0.12065 -0.305054)
			(stroke
				(width 0.1)
				(type default)
			)
			(layer "F.Fab")
		)
		(fp_line
			(start -0.67945 0.3048)
			(end -0.67945 -0.305054)
			(stroke
				(width 0.1)
				(type default)
			)
			(layer "F.Fab")
		)
		(fp_line
			(start -0.12065 -0.305054)
			(end -0.12065 -0.2794)
			(stroke
				(width 0.1)
				(type default)
			)
			(layer "F.Fab")
		)
		(fp_line
			(start -0.12065 -0.2794)
			(end 0.12065 -0.2794)
			(stroke
				(width 0.1)
				(type default)
			)
			(layer "F.Fab")
		)
		(fp_line
			(start -0.12065 0.2794)
			(end -0.12065 0.3048)
			(stroke
				(width 0.1)
				(type default)
			)
			(layer "F.Fab")
		)
		(fp_line
			(start -0.12065 0.3048)
			(end -0.67945 0.3048)
			(stroke
				(width 0.1)
				(type default)
			)
			(layer "F.Fab")
		)
		(fp_line
			(start 0.120396 0.2794)
			(end -0.12065 0.2794)
			(stroke
				(width 0.1)
				(type default)
			)
			(layer "F.Fab")
		)
		(fp_line
			(start 0.120396 0.3048)
			(end 0.120396 0.2794)
			(stroke
				(width 0.1)
				(type default)
			)
			(layer "F.Fab")
		)
		(fp_line
			(start 0.12065 -0.3048)
			(end 0.67945 -0.3048)
			(stroke
				(width 0.1)
				(type default)
			)
			(layer "F.Fab")
		)
		(fp_line
			(start 0.12065 -0.2794)
			(end 0.12065 -0.3048)
			(stroke
				(width 0.1)
				(type default)
			)
			(layer "F.Fab")
		)
		(fp_line
			(start 0.67945 -0.3048)
			(end 0.67945 0.3048)
			(stroke
				(width 0.1)
				(type default)
			)
			(layer "F.Fab")
		)
		(fp_line
			(start 0.67945 0.3048)
			(end 0.120396 0.3048)
			(stroke
				(width 0.1)
				(type default)
			)
			(layer "F.Fab")
		)
		(pad "1" smd circle
			(at -0.40005 0)
			(size 0 0)
			(layers "F.Cu" "F.Mask" "F.Paste")
			(net "PVDD18_S5_P0")
		)
		(pad "2" smd circle
			(at 0.40005 0)
			(size 0 0)
			(layers "F.Cu" "F.Mask" "F.Paste")
			(net "CPU0_HDT_BYPASS_SEL")
		)
	)
	(footprint ""
		(layer "F.Cu")
		(at 287.92551 -360.420158 90)
		(property "Reference" "PL19"
			(at -3.0734 -3.876548 90)
			(unlocked yes)
			(layer "F.SilkS")
			(effects
				(font
					(size 0.7874 0.5842)
					(thickness 0.1524)
				)
				(justify left)
			)
		)
		(property "Value" ""
			(at 0 0 90)
			(layer "F.Fab")
			(effects
				(font
					(size 1.27 1.27)
				)
			)
		)
		(duplicate_pad_numbers_are_jumpers no)
		(fp_line
			(start 3.050032 -2.999994)
			(end -3.050032 -2.999994)
			(stroke
				(width 0.1524)
				(type default)
			)
			(layer "F.SilkS")
		)
		(fp_line
			(start -3.050032 -2.999994)
			(end -3.050032 -1.4478)
			(stroke
				(width 0.1524)
				(type default)
			)
			(layer "F.SilkS")
		)
		(fp_line
			(start 3.050032 -1.4478)
			(end 3.050032 -2.999994)
			(stroke
				(width 0.1524)
				(type default)
			)
			(layer "F.SilkS")
		)
		(fp_line
			(start -3.050032 1.4478)
			(end -3.050032 2.999994)
			(stroke
				(width 0.1524)
				(type default)
			)
			(layer "F.SilkS")
		)
		(fp_line
			(start 3.050032 2.999994)
			(end 3.050032 1.4478)
			(stroke
				(width 0.1524)
				(type default)
			)
			(layer "F.SilkS")
		)
		(fp_line
			(start -3.050032 2.999994)
			(end 3.050032 2.999994)
			(stroke
				(width 0.1524)
				(type default)
			)
			(layer "F.SilkS")
		)
		(fp_line
			(start 3.050032 -2.999994)
			(end -3.050032 -2.999994)
			(stroke
				(width 0.1)
				(type default)
			)
			(layer "F.Fab")
		)
		(fp_line
			(start -3.050032 -2.999994)
			(end -3.050032 2.999994)
			(stroke
				(width 0.1)
				(type default)
			)
			(layer "F.Fab")
		)
		(fp_line
			(start 3.050032 2.999994)
			(end 3.050032 -2.999994)
			(stroke
				(width 0.1)
				(type default)
			)
			(layer "F.Fab")
		)
		(fp_line
			(start -3.050032 2.999994)
			(end 3.050032 2.999994)
			(stroke
				(width 0.1)
				(type default)
			)
			(layer "F.Fab")
		)
		(pad "1" smd rect
			(at -2.525014 0 90)
			(size 1.651 2.6162)
			(layers "F.Cu" "F.Mask" "F.Paste")
			(net "SW_P12V_AUX_PVDDIO_P0_FLT")
		)
		(pad "2" smd rect
			(at 2.525014 0 90)
			(size 1.651 2.6162)
			(layers "F.Cu" "F.Mask" "F.Paste")
			(net "P12V_AUX")
		)
	)
)
